(kicad_pcb
	(version 20260206)
	(generator "pcbnew")
	(generator_version "10.0")
	(general
		(thickness 1.6)
		(legacy_teardrops no)
	)
	(paper "A4")
	(title_block
		(title "01162023_DA0F0TEBIF0_F0T_Expander_BD_F_brd_V02_OCP.brd")
		(comment 1 "Grand Teton / footprints 5335-5339 of 9728")
	)
	(layers
		(0 "F.Cu" signal "TOP")
		(4 "In1.Cu" signal "GND")
		(6 "In2.Cu" signal "VCC")
		(8 "In3.Cu" signal "VCC1")
		(10 "In4.Cu" signal "GND1")
		(12 "In5.Cu" signal "IN1")
		(14 "In6.Cu" signal "GND2")
		(16 "In7.Cu" signal "IN2")
		(18 "In8.Cu" signal "GND3")
		(20 "In9.Cu" signal "IN3")
		(22 "In10.Cu" signal "GND4")
		(24 "In11.Cu" signal "IN4")
		(26 "In12.Cu" signal "GND5")
		(28 "In13.Cu" signal "IN5")
		(30 "In14.Cu" signal "GND6")
		(32 "In15.Cu" signal "IN6")
		(34 "In16.Cu" signal "GND7")
		(2 "B.Cu" signal "BOTTOM")
		(9 "F.Adhes" user "F.Adhesive")
		(11 "B.Adhes" user "B.Adhesive")
		(13 "F.Paste" user "Package Geometry/Pastemask Top")
		(15 "B.Paste" user "Package Geometry/Pastemask Bottom")
		(5 "F.SilkS" user "Ref Des/Silkscreen Top")
		(7 "B.SilkS" user "Ref Des/Silkscreen Bottom")
		(1 "F.Mask" user "Board Geometry/Soldermask Top")
		(3 "B.Mask" user "Board Geometry/Soldermask Bottom")
		(17 "Dwgs.User" user "User.Drawings")
		(19 "Cmts.User" user "User.Comments")
		(21 "Eco1.User" user "User.Eco1")
		(23 "Eco2.User" user "User.Eco2")
		(25 "Edge.Cuts" user "Board Geometry/Outline")
		(27 "Margin" user)
		(31 "F.CrtYd" user "Package Geometry/Place Bound Top")
		(29 "B.CrtYd" user "Package Geometry/Place Bound Bottom")
		(35 "F.Fab" user "Ref Des/Assembly Top")
		(33 "B.Fab" user "Ref Des/Assembly Bottom")
	)
	(footprint ""
		(layer "F.Cu")
		(at 205.749652 -270.89989)
		(property "Reference" "H98"
			(at -2.32664 -8.786876 0)
			(unlocked yes)
			(layer "F.SilkS")
			(effects
				(font
					(size 0.7874 0.5842)
					(thickness 0.1524)
				)
				(justify left)
			)
		)
		(property "Value" ""
			(at 0 0 0)
			(layer "F.Fab")
			(effects
				(font
					(size 1.27 1.27)
				)
			)
		)
		(duplicate_pad_numbers_are_jumpers no)
		(fp_arc
			(start -5.489702 -5.819394)
			(mid 3.168767 -7.345623)
			(end 7.999984 0)
			(stroke
				(width 0.1524)
				(type default)
			)
			(layer "F.SilkS")
		)
		(fp_arc
			(start 7.999984 0)
			(mid -0.430148 7.988434)
			(end -7.953756 -0.859028)
			(stroke
				(width 0.1524)
				(type default)
			)
			(layer "F.SilkS")
		)
		(fp_arc
			(start -5.46735 -5.839968)
			(mid 3.182835 -7.339591)
			(end 7.999984 0)
			(stroke
				(width 0.1524)
				(type default)
			)
			(layer "B.SilkS")
		)
		(fp_arc
			(start 7.999984 0)
			(mid -0.459169 7.986684)
			(end -7.947152 -0.91694)
			(stroke
				(width 0.1524)
				(type default)
			)
			(layer "B.SilkS")
		)
		(fp_circle
			(center 0 0)
			(end 7.999984 0)
			(stroke
				(width 0.1)
				(type default)
			)
			(fill no)
			(layer "B.Fab")
		)
		(fp_circle
			(center 0 0)
			(end 7.999984 0)
			(stroke
				(width 0.1)
				(type default)
			)
			(fill no)
			(layer "F.Fab")
		)
		(pad "" np_thru_hole circle
			(at 0 0)
			(size 4.5212 4.5212)
			(drill 4.5212)
			(layers "*.Cu" "*.Mask")
			(clearance 0.381)
			(thermal_gap 0.381)
		)
		(pad "2" thru_hole circle
			(at 3.6322 0)
			(size 0.762 0.762)
			(drill 0.5588)
			(layers "*.Cu" "*.Mask")
			(remove_unused_layers no)
			(net "GND")
			(clearance 0.1524)
			(thermal_gap 0.1524)
		)
		(pad "3" thru_hole circle
			(at 2.568448 -2.568448)
			(size 0.762 0.762)
			(drill 0.5588)
			(layers "*.Cu" "*.Mask")
			(remove_unused_layers no)
			(net "GND")
			(clearance 0.1524)
			(thermal_gap 0.1524)
		)
		(pad "4" thru_hole circle
			(at 0 -3.6322)
			(size 0.762 0.762)
			(drill 0.5588)
			(layers "*.Cu" "*.Mask")
			(remove_unused_layers no)
			(net "GND")
			(clearance 0.1524)
			(thermal_gap 0.1524)
		)
		(pad "5" thru_hole circle
			(at -2.568448 -2.568448)
			(size 0.762 0.762)
			(drill 0.5588)
			(layers "*.Cu" "*.Mask")
			(remove_unused_layers no)
			(net "GND")
			(clearance 0.1524)
			(thermal_gap 0.1524)
		)
		(pad "6" thru_hole circle
			(at -3.6322 0)
			(size 0.762 0.762)
			(drill 0.5588)
			(layers "*.Cu" "*.Mask")
			(remove_unused_layers no)
			(net "GND")
			(clearance 0.1524)
			(thermal_gap 0.1524)
		)
		(pad "7" thru_hole circle
			(at -2.568448 2.568448)
			(size 0.762 0.762)
			(drill 0.5588)
			(layers "*.Cu" "*.Mask")
			(remove_unused_layers no)
			(net "GND")
			(clearance 0.1524)
			(thermal_gap 0.1524)
		)
		(pad "8" thru_hole circle
			(at 0 3.6322)
			(size 0.762 0.762)
			(drill 0.5588)
			(layers "*.Cu" "*.Mask")
			(remove_unused_layers no)
			(net "GND")
			(clearance 0.1524)
			(thermal_gap 0.1524)
		)
		(pad "9" thru_hole circle
			(at 2.568448 2.568448)
			(size 0.762 0.762)
			(drill 0.5588)
			(layers "*.Cu" "*.Mask")
			(remove_unused_layers no)
			(net "GND")
			(clearance 0.1524)
			(thermal_gap 0.1524)
		)
		(zone
			(layer "F.Cu")
			(hatch none 0.5)
			(connect_pads
				(clearance 0)
			)
			(min_thickness 0.25)
			(keepout
				(tracks not_allowed)
				(vias allowed)
				(pads allowed)
				(copperpour not_allowed)
				(footprints allowed)
			)
			(placement
				(enabled no)
				(sheetname "")
			)
			(fill
				(thermal_gap 0.5)
				(thermal_bridge_width 0.5)
				(island_removal_mode 0)
			)
			(polygon
				(pts
					(arc
						(start 205.749652 -262.899906)
						(mid 197.749668 -270.89989)
						(end 205.749652 -278.899874)
					)
					(arc
						(start 205.749652 -275.64969)
						(mid 200.999852 -270.89989)
						(end 205.749652 -266.15009)
					)
				)
			)
		)
		(zone
			(layer "F.Cu")
			(hatch none 0.5)
			(connect_pads
				(clearance 0)
			)
			(min_thickness 0.25)
			(keepout
				(tracks not_allowed)
				(vias allowed)
				(pads allowed)
				(copperpour not_allowed)
				(footprints allowed)
			)
			(placement
				(enabled no)
				(sheetname "")
			)
			(fill
				(thermal_gap 0.5)
				(thermal_bridge_width 0.5)
				(island_removal_mode 0)
			)
			(polygon
				(pts
					(arc
						(start 205.749652 -262.899906)
						(mid 213.749636 -270.89989)
						(end 205.749652 -278.899874)
					)
					(arc
						(start 205.749652 -275.64969)
						(mid 210.499452 -270.89989)
						(end 205.749652 -266.15009)
					)
				)
			)
		)
		(zone
			(layers "F.Cu" "B.Cu" "In1.Cu" "In2.Cu" "In3.Cu" "In4.Cu" "In5.Cu" "In6.Cu"
				"In7.Cu" "In8.Cu" "In9.Cu" "In10.Cu" "In11.Cu" "In12.Cu" "In13.Cu" "In14.Cu"
				"In15.Cu" "In16.Cu"
			)
			(hatch none 0.5)
			(connect_pads
				(clearance 0)
			)
			(min_thickness 0.25)
			(keepout
				(tracks not_allowed)
				(vias allowed)
				(pads allowed)
				(copperpour not_allowed)
				(footprints allowed)
			)
			(placement
				(enabled no)
				(sheetname "")
			)
			(fill
				(thermal_gap 0.5)
				(thermal_bridge_width 0.5)
				(island_removal_mode 0)
			)
			(polygon
				(pts
					(arc
						(start 208.515712 -270.89989)
						(mid 202.983592 -270.89989)
						(end 208.515712 -270.89989)
					)
				)
			)
		)
		(zone
			(layer "B.Cu")
			(hatch none 0.5)
			(connect_pads
				(clearance 0)
			)
			(min_thickness 0.25)
			(keepout
				(tracks not_allowed)
				(vias allowed)
				(pads allowed)
				(copperpour not_allowed)
				(footprints allowed)
			)
			(placement
				(enabled no)
				(sheetname "")
			)
			(fill
				(thermal_gap 0.5)
				(thermal_bridge_width 0.5)
				(island_removal_mode 0)
			)
			(polygon
				(pts
					(arc
						(start 205.749652 -265.89609)
						(mid 200.745852 -270.89989)
						(end 205.749652 -275.90369)
					)
					(arc
						(start 205.749652 -275.42109)
						(mid 201.228452 -270.89989)
						(end 205.749652 -266.37869)
					)
				)
			)
		)
		(zone
			(layer "B.Cu")
			(hatch none 0.5)
			(connect_pads
				(clearance 0)
			)
			(min_thickness 0.25)
			(keepout
				(tracks not_allowed)
				(vias allowed)
				(pads allowed)
				(copperpour not_allowed)
				(footprints allowed)
			)
			(placement
				(enabled no)
				(sheetname "")
			)
			(fill
				(thermal_gap 0.5)
				(thermal_bridge_width 0.5)
				(island_removal_mode 0)
			)
			(polygon
				(pts
					(arc
						(start 205.749652 -265.89609)
						(mid 210.753452 -270.89989)
						(end 205.749652 -275.90369)
					)
					(arc
						(start 205.749652 -275.42109)
						(mid 210.270852 -270.89989)
						(end 205.749652 -266.37869)
					)
				)
			)
		)
	)
	(footprint ""
		(layer "F.Cu")
		(at 462.465674 -274.61083)
		(property "Reference" "R806"
			(at 0 0 0)
			(layer "F.SilkS")
			(hide yes)
			(effects
				(font
					(size 1.27 1.27)
				)
			)
		)
		(property "Value" ""
			(at 0 0 0)
			(layer "F.Fab")
			(effects
				(font
					(size 1.27 1.27)
				)
			)
		)
		(duplicate_pad_numbers_are_jumpers no)
		(fp_line
			(start -0.7874 -0.4064)
			(end 0.7874 -0.4064)
			(stroke
				(width 0.1524)
				(type default)
			)
			(layer "F.SilkS")
		)
		(fp_line
			(start -0.7874 0.4064)
			(end -0.7874 -0.4064)
			(stroke
				(width 0.1524)
				(type default)
			)
			(layer "F.SilkS")
		)
		(fp_line
			(start 0.7874 -0.4064)
			(end 0.7874 0.4064)
			(stroke
				(width 0.1524)
				(type default)
			)
			(layer "F.SilkS")
		)
		(fp_line
			(start 0.7874 0.4064)
			(end -0.7874 0.4064)
			(stroke
				(width 0.1524)
				(type default)
			)
			(layer "F.SilkS")
		)
		(fp_line
			(start -0.67945 -0.305054)
			(end -0.12065 -0.305054)
			(stroke
				(width 0.1)
				(type default)
			)
			(layer "F.Fab")
		)
		(fp_line
			(start -0.67945 0.3048)
			(end -0.67945 -0.305054)
			(stroke
				(width 0.1)
				(type default)
			)
			(layer "F.Fab")
		)
		(fp_line
			(start -0.12065 -0.305054)
			(end -0.12065 -0.2794)
			(stroke
				(width 0.1)
				(type default)
			)
			(layer "F.Fab")
		)
		(fp_line
			(start -0.12065 -0.2794)
			(end 0.12065 -0.2794)
			(stroke
				(width 0.1)
				(type default)
			)
			(layer "F.Fab")
		)
		(fp_line
			(start -0.12065 0.2794)
			(end -0.12065 0.3048)
			(stroke
				(width 0.1)
				(type default)
			)
			(layer "F.Fab")
		)
		(fp_line
			(start -0.12065 0.3048)
			(end -0.67945 0.3048)
			(stroke
				(width 0.1)
				(type default)
			)
			(layer "F.Fab")
		)
		(fp_line
			(start 0.120396 0.2794)
			(end -0.12065 0.2794)
			(stroke
				(width 0.1)
				(type default)
			)
			(layer "F.Fab")
		)
		(fp_line
			(start 0.120396 0.3048)
			(end 0.120396 0.2794)
			(stroke
				(width 0.1)
				(type default)
			)
			(layer "F.Fab")
		)
		(fp_line
			(start 0.12065 -0.3048)
			(end 0.67945 -0.3048)
			(stroke
				(width 0.1)
				(type default)
			)
			(layer "F.Fab")
		)
		(fp_line
			(start 0.12065 -0.2794)
			(end 0.12065 -0.3048)
			(stroke
				(width 0.1)
				(type default)
			)
			(layer "F.Fab")
		)
		(fp_line
			(start 0.67945 -0.3048)
			(end 0.67945 0.3048)
			(stroke
				(width 0.1)
				(type default)
			)
			(layer "F.Fab")
		)
		(fp_line
			(start 0.67945 0.3048)
			(end 0.120396 0.3048)
			(stroke
				(width 0.1)
				(type default)
			)
			(layer "F.Fab")
		)
		(pad "1" smd circle
			(at -0.40005 0)
			(size 0 0)
			(layers "F.Cu" "F.Mask" "F.Paste")
			(net "PEX3_P1V25_ADC_A1")
		)
		(pad "2" smd circle
			(at 0.40005 0)
			(size 0 0)
			(layers "F.Cu" "F.Mask" "F.Paste")
			(net "GND")
		)
	)
	(footprint ""
		(layer "F.Cu")
		(at 426.567092 -57.332626)
		(property "Reference" "R6827"
			(at 0 0 0)
			(layer "F.SilkS")
			(hide yes)
			(effects
				(font
					(size 1.27 1.27)
				)
			)
		)
		(property "Value" ""
			(at 0 0 0)
			(layer "F.Fab")
			(effects
				(font
					(size 1.27 1.27)
				)
			)
		)
		(duplicate_pad_numbers_are_jumpers no)
		(fp_line
			(start -0.7874 -0.4064)
			(end 0.7874 -0.4064)
			(stroke
				(width 0.1524)
				(type default)
			)
			(layer "F.SilkS")
		)
		(fp_line
			(start -0.7874 0.4064)
			(end -0.7874 -0.4064)
			(stroke
				(width 0.1524)
				(type default)
			)
			(layer "F.SilkS")
		)
		(fp_line
			(start 0.7874 -0.4064)
			(end 0.7874 0.4064)
			(stroke
				(width 0.1524)
				(type default)
			)
			(layer "F.SilkS")
		)
		(fp_line
			(start 0.7874 0.4064)
			(end -0.7874 0.4064)
			(stroke
				(width 0.1524)
				(type default)
			)
			(layer "F.SilkS")
		)
		(fp_line
			(start -0.67945 -0.305054)
			(end -0.12065 -0.305054)
			(stroke
				(width 0.1)
				(type default)
			)
			(layer "F.Fab")
		)
		(fp_line
			(start -0.67945 0.3048)
			(end -0.67945 -0.305054)
			(stroke
				(width 0.1)
				(type default)
			)
			(layer "F.Fab")
		)
		(fp_line
			(start -0.12065 -0.305054)
			(end -0.12065 -0.2794)
			(stroke
				(width 0.1)
				(type default)
			)
			(layer "F.Fab")
		)
		(fp_line
			(start -0.12065 -0.2794)
			(end 0.12065 -0.2794)
			(stroke
				(width 0.1)
				(type default)
			)
			(layer "F.Fab")
		)
		(fp_line
			(start -0.12065 0.2794)
			(end -0.12065 0.3048)
			(stroke
				(width 0.1)
				(type default)
			)
			(layer "F.Fab")
		)
		(fp_line
			(start -0.12065 0.3048)
			(end -0.67945 0.3048)
			(stroke
				(width 0.1)
				(type default)
			)
			(layer "F.Fab")
		)
		(fp_line
			(start 0.120396 0.2794)
			(end -0.12065 0.2794)
			(stroke
				(width 0.1)
				(type default)
			)
			(layer "F.Fab")
		)
		(fp_line
			(start 0.120396 0.3048)
			(end 0.120396 0.2794)
			(stroke
				(width 0.1)
				(type default)
			)
			(layer "F.Fab")
		)
		(fp_line
			(start 0.12065 -0.3048)
			(end 0.67945 -0.3048)
			(stroke
				(width 0.1)
				(type default)
			)
			(layer "F.Fab")
		)
		(fp_line
			(start 0.12065 -0.2794)
			(end 0.12065 -0.3048)
			(stroke
				(width 0.1)
				(type default)
			)
			(layer "F.Fab")
		)
		(fp_line
			(start 0.67945 -0.3048)
			(end 0.67945 0.3048)
			(stroke
				(width 0.1)
				(type default)
			)
			(layer "F.Fab")
		)
		(fp_line
			(start 0.67945 0.3048)
			(end 0.120396 0.3048)
			(stroke
				(width 0.1)
				(type default)
			)
			(layer "F.Fab")
		)
		(pad "1" smd circle
			(at -0.40005 0)
			(size 0 0)
			(layers "F.Cu" "F.Mask" "F.Paste")
			(net "SSD14_PWR_EN_R")
		)
		(pad "2" smd circle
			(at 0.40005 0)
			(size 0 0)
			(layers "F.Cu" "F.Mask" "F.Paste")
			(net "GND")
		)
	)
	(footprint ""
		(layer "F.Cu")
		(at 259.58673 -307.803296 -135)
		(property "Reference" "R1329"
			(at 0 0 225)
			(layer "F.SilkS")
			(hide yes)
			(effects
				(font
					(size 1.27 1.27)
				)
			)
		)
		(property "Value" ""
			(at 0 0 225)
			(layer "F.Fab")
			(effects
				(font
					(size 1.27 1.27)
				)
			)
		)
		(duplicate_pad_numbers_are_jumpers no)
		(fp_line
			(start 0.787389 0.406267)
			(end -0.787389 0.406267)
			(stroke
				(width 0.1524)
				(type default)
			)
			(layer "F.SilkS")
		)
		(fp_line
			(start 0.787389 -0.406267)
			(end 0.787389 0.406267)
			(stroke
				(width 0.1524)
				(type default)
			)
			(layer "F.SilkS")
		)
		(fp_line
			(start -0.787389 0.406267)
			(end -0.787389 -0.406267)
			(stroke
				(width 0.1524)
				(type default)
			)
			(layer "F.SilkS")
		)
		(fp_line
			(start -0.787389 -0.406267)
			(end 0.787389 -0.406267)
			(stroke
				(width 0.1524)
				(type default)
			)
			(layer "F.SilkS")
		)
		(fp_line
			(start 0.679446 0.30479)
			(end 0.120515 0.30479)
			(stroke
				(width 0.1)
				(type default)
			)
			(layer "F.Fab")
		)
		(fp_line
			(start 0.120515 0.30479)
			(end 0.120335 0.279466)
			(stroke
				(width 0.1)
				(type default)
			)
			(layer "F.Fab")
		)
		(fp_line
			(start 0.120335 0.279466)
			(end -0.120695 0.279466)
			(stroke
				(width 0.1)
				(type default)
			)
			(layer "F.Fab")
		)
		(fp_line
			(start 0.679446 -0.30479)
			(end 0.679446 0.30479)
			(stroke
				(width 0.1)
				(type default)
			)
			(layer "F.Fab")
		)
		(fp_line
			(start -0.120515 0.30479)
			(end -0.679446 0.30479)
			(stroke
				(width 0.1)
				(type default)
			)
			(layer "F.Fab")
		)
		(fp_line
			(start -0.120695 0.279466)
			(end -0.120515 0.30479)
			(stroke
				(width 0.1)
				(type default)
			)
			(layer "F.Fab")
		)
		(fp_line
			(start 0.120695 -0.279466)
			(end 0.120515 -0.30479)
			(stroke
				(width 0.1)
				(type default)
			)
			(layer "F.Fab")
		)
		(fp_line
			(start 0.120515 -0.30479)
			(end 0.679446 -0.30479)
			(stroke
				(width 0.1)
				(type default)
			)
			(layer "F.Fab")
		)
		(fp_line
			(start -0.679446 0.30479)
			(end -0.679446 -0.305149)
			(stroke
				(width 0.1)
				(type default)
			)
			(layer "F.Fab")
		)
		(fp_line
			(start -0.120695 -0.279466)
			(end 0.120695 -0.279466)
			(stroke
				(width 0.1)
				(type default)
			)
			(layer "F.Fab")
		)
		(fp_line
			(start -0.120695 -0.304969)
			(end -0.120695 -0.279466)
			(stroke
				(width 0.1)
				(type default)
			)
			(layer "F.Fab")
		)
		(fp_line
			(start -0.679446 -0.305149)
			(end -0.120695 -0.304969)
			(stroke
				(width 0.1)
				(type default)
			)
			(layer "F.Fab")
		)
		(pad "1" smd circle
			(at -0.40005 0 225)
			(size 0 0)
			(layers "F.Cu" "F.Mask" "F.Paste")
			(net "PEX2_DBG_SEL0")
		)
		(pad "2" smd circle
			(at 0.40005 0 225)
			(size 0 0)
			(layers "F.Cu" "F.Mask" "F.Paste")
			(net "P1V8_PEX")
		)
	)
	(footprint ""
		(layer "F.Cu")
		(at 11.647932 -255.046734 -90)
		(property "Reference" "R6464"
			(at 0 0 270)
			(layer "F.SilkS")
			(hide yes)
			(effects
				(font
					(size 1.27 1.27)
				)
			)
		)
		(property "Value" ""
			(at 0 0 270)
			(layer "F.Fab")
			(effects
				(font
					(size 1.27 1.27)
				)
			)
		)
		(duplicate_pad_numbers_are_jumpers no)
		(fp_line
			(start -0.7874 0.4064)
			(end -0.7874 -0.4064)
			(stroke
				(width 0.1524)
				(type default)
			)
			(layer "F.SilkS")
		)
		(fp_line
			(start 0.7874 0.4064)
			(end -0.7874 0.4064)
			(stroke
				(width 0.1524)
				(type default)
			)
			(layer "F.SilkS")
		)
		(fp_line
			(start -0.7874 -0.4064)
			(end 0.7874 -0.4064)
			(stroke
				(width 0.1524)
				(type default)
			)
			(layer "F.SilkS")
		)
		(fp_line
			(start 0.7874 -0.4064)
			(end 0.7874 0.4064)
			(stroke
				(width 0.1524)
				(type default)
			)
			(layer "F.SilkS")
		)
		(fp_line
			(start -0.67945 0.3048)
			(end -0.67945 -0.305054)
			(stroke
				(width 0.1)
				(type default)
			)
			(layer "F.Fab")
		)
		(fp_line
			(start -0.12065 0.3048)
			(end -0.67945 0.3048)
			(stroke
				(width 0.1)
				(type default)
			)
			(layer "F.Fab")
		)
		(fp_line
			(start 0.120396 0.3048)
			(end 0.120396 0.2794)
			(stroke
				(width 0.1)
				(type default)
			)
			(layer "F.Fab")
		)
		(fp_line
			(start 0.67945 0.3048)
			(end 0.120396 0.3048)
			(stroke
				(width 0.1)
				(type default)
			)
			(layer "F.Fab")
		)
		(fp_line
			(start -0.12065 0.2794)
			(end -0.12065 0.3048)
			(stroke
				(width 0.1)
				(type default)
			)
			(layer "F.Fab")
		)
		(fp_line
			(start 0.120396 0.2794)
			(end -0.12065 0.2794)
			(stroke
				(width 0.1)
				(type default)
			)
			(layer "F.Fab")
		)
		(fp_line
			(start -0.12065 -0.2794)
			(end 0.12065 -0.2794)
			(stroke
				(width 0.1)
				(type default)
			)
			(layer "F.Fab")
		)
		(fp_line
			(start 0.12065 -0.2794)
			(end 0.12065 -0.3048)
			(stroke
				(width 0.1)
				(type default)
			)
			(layer "F.Fab")
		)
		(fp_line
			(start 0.12065 -0.3048)
			(end 0.67945 -0.3048)
			(stroke
				(width 0.1)
				(type default)
			)
			(layer "F.Fab")
		)
		(fp_line
			(start 0.67945 -0.3048)
			(end 0.67945 0.3048)
			(stroke
				(width 0.1)
				(type default)
			)
			(layer "F.Fab")
		)
		(fp_line
			(start -0.67945 -0.305054)
			(end -0.12065 -0.305054)
			(stroke
				(width 0.1)
				(type default)
			)
			(layer "F.Fab")
		)
		(fp_line
			(start -0.12065 -0.305054)
			(end -0.12065 -0.2794)
			(stroke
				(width 0.1)
				(type default)
			)
			(layer "F.Fab")
		)
		(pad "1" smd circle
			(at -0.40005 0 270)
			(size 0 0)
			(layers "F.Cu" "F.Mask" "F.Paste")
			(net "P1V25_SERDES_VDDPLL_PEX0")
		)
		(pad "2" smd circle
			(at 0.40005 0 270)
			(size 0 0)
			(layers "F.Cu" "F.Mask" "F.Paste")
			(net "P1V25_SERDES_VDDPLL_PEX0_C3")
		)
	)
)
